(kicad_pcb
	(version 20260206)
	(generator "pcbnew")
	(generator_version "10.0")
	(general
		(thickness 1.6)
		(legacy_teardrops no)
	)
	(paper "A4")
	(title_block
		(title "01162023_DA0F0TEBIF0_F0T_Expander_BD_F_brd_V02_OCP.brd")
		(comment 1 "Grand Teton / footprints 5865-5870 of 9728")
	)
	(layers
		(0 "F.Cu" signal "TOP")
		(4 "In1.Cu" signal "GND")
		(6 "In2.Cu" signal "VCC")
		(8 "In3.Cu" signal "VCC1")
		(10 "In4.Cu" signal "GND1")
		(12 "In5.Cu" signal "IN1")
		(14 "In6.Cu" signal "GND2")
		(16 "In7.Cu" signal "IN2")
		(18 "In8.Cu" signal "GND3")
		(20 "In9.Cu" signal "IN3")
		(22 "In10.Cu" signal "GND4")
		(24 "In11.Cu" signal "IN4")
		(26 "In12.Cu" signal "GND5")
		(28 "In13.Cu" signal "IN5")
		(30 "In14.Cu" signal "GND6")
		(32 "In15.Cu" signal "IN6")
		(34 "In16.Cu" signal "GND7")
		(2 "B.Cu" signal "BOTTOM")
		(9 "F.Adhes" user "F.Adhesive")
		(11 "B.Adhes" user "B.Adhesive")
		(13 "F.Paste" user "Package Geometry/Pastemask Top")
		(15 "B.Paste" user "Package Geometry/Pastemask Bottom")
		(5 "F.SilkS" user "Ref Des/Silkscreen Top")
		(7 "B.SilkS" user "Ref Des/Silkscreen Bottom")
		(1 "F.Mask" user "Board Geometry/Soldermask Top")
		(3 "B.Mask" user "Board Geometry/Soldermask Bottom")
		(17 "Dwgs.User" user "User.Drawings")
		(19 "Cmts.User" user "User.Comments")
		(21 "Eco1.User" user "User.Eco1")
		(23 "Eco2.User" user "User.Eco2")
		(25 "Edge.Cuts" user "Board Geometry/Outline")
		(27 "Margin" user)
		(31 "F.CrtYd" user "Package Geometry/Place Bound Top")
		(29 "B.CrtYd" user "Package Geometry/Place Bound Bottom")
		(35 "F.Fab" user "Ref Des/Assembly Top")
		(33 "B.Fab" user "Ref Des/Assembly Bottom")
	)
	(footprint ""
		(layer "F.Cu")
		(at 247.10771 -154.510994)
		(property "Reference" "PC803"
			(at 0 0 0)
			(layer "F.SilkS")
			(hide yes)
			(effects
				(font
					(size 1.27 1.27)
				)
			)
		)
		(property "Value" ""
			(at 0 0 0)
			(layer "F.Fab")
			(effects
				(font
					(size 1.27 1.27)
				)
			)
		)
		(duplicate_pad_numbers_are_jumpers no)
		(fp_line
			(start -0.7874 -0.4064)
			(end 0.7874 -0.4064)
			(stroke
				(width 0.1524)
				(type default)
			)
			(layer "F.SilkS")
		)
		(fp_line
			(start -0.7874 0.4064)
			(end -0.7874 -0.4064)
			(stroke
				(width 0.1524)
				(type default)
			)
			(layer "F.SilkS")
		)
		(fp_line
			(start 0.7874 -0.4064)
			(end 0.7874 0.4064)
			(stroke
				(width 0.1524)
				(type default)
			)
			(layer "F.SilkS")
		)
		(fp_line
			(start 0.7874 0.4064)
			(end -0.7874 0.4064)
			(stroke
				(width 0.1524)
				(type default)
			)
			(layer "F.SilkS")
		)
		(fp_line
			(start -0.67945 -0.305054)
			(end -0.12065 -0.305054)
			(stroke
				(width 0.1)
				(type default)
			)
			(layer "F.Fab")
		)
		(fp_line
			(start -0.67945 0.3048)
			(end -0.67945 -0.305054)
			(stroke
				(width 0.1)
				(type default)
			)
			(layer "F.Fab")
		)
		(fp_line
			(start -0.12065 -0.305054)
			(end -0.12065 -0.2794)
			(stroke
				(width 0.1)
				(type default)
			)
			(layer "F.Fab")
		)
		(fp_line
			(start -0.12065 -0.2794)
			(end 0.12065 -0.2794)
			(stroke
				(width 0.1)
				(type default)
			)
			(layer "F.Fab")
		)
		(fp_line
			(start -0.12065 0.2794)
			(end -0.12065 0.3048)
			(stroke
				(width 0.1)
				(type default)
			)
			(layer "F.Fab")
		)
		(fp_line
			(start -0.12065 0.3048)
			(end -0.67945 0.3048)
			(stroke
				(width 0.1)
				(type default)
			)
			(layer "F.Fab")
		)
		(fp_line
			(start 0.120396 0.2794)
			(end -0.12065 0.2794)
			(stroke
				(width 0.1)
				(type default)
			)
			(layer "F.Fab")
		)
		(fp_line
			(start 0.120396 0.3048)
			(end 0.120396 0.2794)
			(stroke
				(width 0.1)
				(type default)
			)
			(layer "F.Fab")
		)
		(fp_line
			(start 0.12065 -0.3048)
			(end 0.67945 -0.3048)
			(stroke
				(width 0.1)
				(type default)
			)
			(layer "F.Fab")
		)
		(fp_line
			(start 0.12065 -0.2794)
			(end 0.12065 -0.3048)
			(stroke
				(width 0.1)
				(type default)
			)
			(layer "F.Fab")
		)
		(fp_line
			(start 0.67945 -0.3048)
			(end 0.67945 0.3048)
			(stroke
				(width 0.1)
				(type default)
			)
			(layer "F.Fab")
		)
		(fp_line
			(start 0.67945 0.3048)
			(end 0.120396 0.3048)
			(stroke
				(width 0.1)
				(type default)
			)
			(layer "F.Fab")
		)
		(pad "1" smd circle
			(at -0.40005 0)
			(size 0 0)
			(layers "F.Cu" "F.Mask" "F.Paste")
			(net "P12V_NIC4_R")
		)
		(pad "2" smd circle
			(at 0.40005 0)
			(size 0 0)
			(layers "F.Cu" "F.Mask" "F.Paste")
			(net "GND")
		)
	)
	(footprint ""
		(layer "F.Cu")
		(at 319.79997 -407.960068 180)
		(property "Reference" "J61"
			(at -1.724406 -11.62685 0)
			(unlocked yes)
			(layer "F.SilkS")
			(effects
				(font
					(size 0.7874 0.5842)
					(thickness 0.1524)
				)
			)
		)
		(property "Value" ""
			(at 0 0 180)
			(layer "F.Fab")
			(effects
				(font
					(size 1.27 1.27)
				)
			)
		)
		(duplicate_pad_numbers_are_jumpers no)
		(fp_line
			(start 3.525012 21.310092)
			(end 3.525012 -10.489946)
			(stroke
				(width 0.1524)
				(type default)
			)
			(layer "F.SilkS")
		)
		(fp_line
			(start 3.525012 -10.489946)
			(end -3.525012 -10.489946)
			(stroke
				(width 0.1524)
				(type default)
			)
			(layer "F.SilkS")
		)
		(fp_line
			(start -3.525012 21.310092)
			(end 3.525012 21.310092)
			(stroke
				(width 0.1524)
				(type default)
			)
			(layer "F.SilkS")
		)
		(fp_line
			(start -3.525012 10.6299)
			(end 3.525012 10.6299)
			(stroke
				(width 0.1524)
				(type default)
			)
			(layer "F.SilkS")
		)
		(fp_line
			(start -3.525012 -10.489946)
			(end -3.525012 21.310092)
			(stroke
				(width 0.1524)
				(type default)
			)
			(layer "F.SilkS")
		)
		(fp_line
			(start 3.525012 21.310092)
			(end 3.525012 -10.489946)
			(stroke
				(width 0.1)
				(type default)
			)
			(layer "F.Fab")
		)
		(fp_line
			(start 3.525012 -10.489946)
			(end -3.525012 -10.489946)
			(stroke
				(width 0.1)
				(type default)
			)
			(layer "F.Fab")
		)
		(fp_line
			(start -3.525012 21.310092)
			(end 3.525012 21.310092)
			(stroke
				(width 0.1)
				(type default)
			)
			(layer "F.Fab")
		)
		(fp_line
			(start -3.525012 -10.489946)
			(end -3.525012 21.310092)
			(stroke
				(width 0.1)
				(type default)
			)
			(layer "F.Fab")
		)
		(pad "" np_thru_hole circle
			(at 0 -6.620002 180)
			(size 3.175 3.175)
			(drill 3.175)
			(layers "*.Cu" "*.Mask")
			(clearance 0.381)
			(thermal_gap 0.381)
		)
		(pad "" np_thru_hole circle
			(at 0 0 180)
			(size 0 0)
			(drill 3.175)
			(layers "*.Cu" "*.Mask")
			(clearance 0)
		)
		(pad "" np_thru_hole circle
			(at 0 5.130038 180)
			(size 3.175 3.175)
			(drill 3.175)
			(layers "*.Cu" "*.Mask")
			(clearance 0.381)
			(thermal_gap 0.381)
		)
		(zone
			(layers "F.Cu" "B.Cu" "In1.Cu" "In2.Cu" "In3.Cu" "In4.Cu" "In5.Cu" "In6.Cu"
				"In7.Cu" "In8.Cu" "In9.Cu" "In10.Cu" "In11.Cu" "In12.Cu" "In13.Cu" "In14.Cu"
				"In15.Cu" "In16.Cu"
			)
			(hatch none 0.5)
			(connect_pads
				(clearance 0)
			)
			(min_thickness 0.25)
			(keepout
				(tracks not_allowed)
				(vias allowed)
				(pads allowed)
				(copperpour not_allowed)
				(footprints allowed)
			)
			(placement
				(enabled no)
				(sheetname "")
			)
			(fill
				(thermal_gap 0.5)
				(thermal_bridge_width 0.5)
				(island_removal_mode 0)
			)
			(polygon
				(pts
					(arc
						(start 321.89547 -413.090106)
						(mid 317.70447 -413.090106)
						(end 321.89547 -413.090106)
					)
				)
			)
		)
		(zone
			(layers "F.Cu" "B.Cu" "In1.Cu" "In2.Cu" "In3.Cu" "In4.Cu" "In5.Cu" "In6.Cu"
				"In7.Cu" "In8.Cu" "In9.Cu" "In10.Cu" "In11.Cu" "In12.Cu" "In13.Cu" "In14.Cu"
				"In15.Cu" "In16.Cu"
			)
			(hatch none 0.5)
			(connect_pads
				(clearance 0)
			)
			(min_thickness 0.25)
			(keepout
				(tracks not_allowed)
				(vias allowed)
				(pads allowed)
				(copperpour not_allowed)
				(footprints allowed)
			)
			(placement
				(enabled no)
				(sheetname "")
			)
			(fill
				(thermal_gap 0.5)
				(thermal_bridge_width 0.5)
				(island_removal_mode 0)
			)
			(polygon
				(pts
					(arc
						(start 321.89547 -401.340066)
						(mid 317.70447 -401.340066)
						(end 321.89547 -401.340066)
					)
				)
			)
		)
		(zone
			(layers "F.Cu" "B.Cu" "In1.Cu" "In2.Cu" "In3.Cu" "In4.Cu" "In5.Cu" "In6.Cu"
				"In7.Cu" "In8.Cu" "In9.Cu" "In10.Cu" "In11.Cu" "In12.Cu" "In13.Cu" "In14.Cu"
				"In15.Cu" "In16.Cu"
			)
			(hatch none 0.5)
			(connect_pads
				(clearance 0)
			)
			(min_thickness 0.25)
			(keepout
				(tracks not_allowed)
				(vias allowed)
				(pads allowed)
				(copperpour not_allowed)
				(footprints allowed)
			)
			(placement
				(enabled no)
				(sheetname "")
			)
			(fill
				(thermal_gap 0.5)
				(thermal_bridge_width 0.5)
				(island_removal_mode 0)
			)
			(polygon
				(pts
					(arc
						(start 323.41947 -407.960068)
						(mid 316.18047 -407.960068)
						(end 323.41947 -407.960068)
					)
				)
			)
		)
	)
	(footprint ""
		(layer "F.Cu")
		(at 86.803992 -289.230816 90)
		(property "Reference" "R3947"
			(at 0 0 90)
			(layer "F.SilkS")
			(hide yes)
			(effects
				(font
					(size 1.27 1.27)
				)
			)
		)
		(property "Value" ""
			(at 0 0 90)
			(layer "F.Fab")
			(effects
				(font
					(size 1.27 1.27)
				)
			)
		)
		(duplicate_pad_numbers_are_jumpers no)
		(fp_line
			(start 0.7874 -0.4064)
			(end 0.7874 0.4064)
			(stroke
				(width 0.1524)
				(type default)
			)
			(layer "F.SilkS")
		)
		(fp_line
			(start -0.7874 -0.4064)
			(end 0.7874 -0.4064)
			(stroke
				(width 0.1524)
				(type default)
			)
			(layer "F.SilkS")
		)
		(fp_line
			(start 0.7874 0.4064)
			(end -0.7874 0.4064)
			(stroke
				(width 0.1524)
				(type default)
			)
			(layer "F.SilkS")
		)
		(fp_line
			(start -0.7874 0.4064)
			(end -0.7874 -0.4064)
			(stroke
				(width 0.1524)
				(type default)
			)
			(layer "F.SilkS")
		)
		(fp_line
			(start -0.12065 -0.305054)
			(end -0.12065 -0.2794)
			(stroke
				(width 0.1)
				(type default)
			)
			(layer "F.Fab")
		)
		(fp_line
			(start -0.67945 -0.305054)
			(end -0.12065 -0.305054)
			(stroke
				(width 0.1)
				(type default)
			)
			(layer "F.Fab")
		)
		(fp_line
			(start 0.67945 -0.3048)
			(end 0.67945 0.3048)
			(stroke
				(width 0.1)
				(type default)
			)
			(layer "F.Fab")
		)
		(fp_line
			(start 0.12065 -0.3048)
			(end 0.67945 -0.3048)
			(stroke
				(width 0.1)
				(type default)
			)
			(layer "F.Fab")
		)
		(fp_line
			(start 0.12065 -0.2794)
			(end 0.12065 -0.3048)
			(stroke
				(width 0.1)
				(type default)
			)
			(layer "F.Fab")
		)
		(fp_line
			(start -0.12065 -0.2794)
			(end 0.12065 -0.2794)
			(stroke
				(width 0.1)
				(type default)
			)
			(layer "F.Fab")
		)
		(fp_line
			(start 0.120396 0.2794)
			(end -0.12065 0.2794)
			(stroke
				(width 0.1)
				(type default)
			)
			(layer "F.Fab")
		)
		(fp_line
			(start -0.12065 0.2794)
			(end -0.12065 0.3048)
			(stroke
				(width 0.1)
				(type default)
			)
			(layer "F.Fab")
		)
		(fp_line
			(start 0.67945 0.3048)
			(end 0.120396 0.3048)
			(stroke
				(width 0.1)
				(type default)
			)
			(layer "F.Fab")
		)
		(fp_line
			(start 0.120396 0.3048)
			(end 0.120396 0.2794)
			(stroke
				(width 0.1)
				(type default)
			)
			(layer "F.Fab")
		)
		(fp_line
			(start -0.12065 0.3048)
			(end -0.67945 0.3048)
			(stroke
				(width 0.1)
				(type default)
			)
			(layer "F.Fab")
		)
		(fp_line
			(start -0.67945 0.3048)
			(end -0.67945 -0.305054)
			(stroke
				(width 0.1)
				(type default)
			)
			(layer "F.Fab")
		)
		(pad "1" smd circle
			(at -0.40005 0 90)
			(size 0 0)
			(layers "F.Cu" "F.Mask" "F.Paste")
			(net "PWRGD_P1V8_PEX_R")
		)
		(pad "2" smd circle
			(at 0.40005 0 90)
			(size 0 0)
			(layers "F.Cu" "F.Mask" "F.Paste")
			(net "PWRGD_P1V8_PEX0_R")
		)
	)
	(footprint ""
		(layer "F.Cu")
		(at 189.98565 -27.092148 -90)
		(property "Reference" "R5743"
			(at 0 0 270)
			(layer "F.SilkS")
			(hide yes)
			(effects
				(font
					(size 1.27 1.27)
				)
			)
		)
		(property "Value" ""
			(at 0 0 270)
			(layer "F.Fab")
			(effects
				(font
					(size 1.27 1.27)
				)
			)
		)
		(duplicate_pad_numbers_are_jumpers no)
		(fp_line
			(start -0.7874 0.4064)
			(end -0.7874 -0.4064)
			(stroke
				(width 0.1524)
				(type default)
			)
			(layer "F.SilkS")
		)
		(fp_line
			(start 0.7874 0.4064)
			(end -0.7874 0.4064)
			(stroke
				(width 0.1524)
				(type default)
			)
			(layer "F.SilkS")
		)
		(fp_line
			(start -0.7874 -0.4064)
			(end 0.7874 -0.4064)
			(stroke
				(width 0.1524)
				(type default)
			)
			(layer "F.SilkS")
		)
		(fp_line
			(start 0.7874 -0.4064)
			(end 0.7874 0.4064)
			(stroke
				(width 0.1524)
				(type default)
			)
			(layer "F.SilkS")
		)
		(fp_line
			(start -0.67945 0.3048)
			(end -0.67945 -0.305054)
			(stroke
				(width 0.1)
				(type default)
			)
			(layer "F.Fab")
		)
		(fp_line
			(start -0.12065 0.3048)
			(end -0.67945 0.3048)
			(stroke
				(width 0.1)
				(type default)
			)
			(layer "F.Fab")
		)
		(fp_line
			(start 0.120396 0.3048)
			(end 0.120396 0.2794)
			(stroke
				(width 0.1)
				(type default)
			)
			(layer "F.Fab")
		)
		(fp_line
			(start 0.67945 0.3048)
			(end 0.120396 0.3048)
			(stroke
				(width 0.1)
				(type default)
			)
			(layer "F.Fab")
		)
		(fp_line
			(start -0.12065 0.2794)
			(end -0.12065 0.3048)
			(stroke
				(width 0.1)
				(type default)
			)
			(layer "F.Fab")
		)
		(fp_line
			(start 0.120396 0.2794)
			(end -0.12065 0.2794)
			(stroke
				(width 0.1)
				(type default)
			)
			(layer "F.Fab")
		)
		(fp_line
			(start -0.12065 -0.2794)
			(end 0.12065 -0.2794)
			(stroke
				(width 0.1)
				(type default)
			)
			(layer "F.Fab")
		)
		(fp_line
			(start 0.12065 -0.2794)
			(end 0.12065 -0.3048)
			(stroke
				(width 0.1)
				(type default)
			)
			(layer "F.Fab")
		)
		(fp_line
			(start 0.12065 -0.3048)
			(end 0.67945 -0.3048)
			(stroke
				(width 0.1)
				(type default)
			)
			(layer "F.Fab")
		)
		(fp_line
			(start 0.67945 -0.3048)
			(end 0.67945 0.3048)
			(stroke
				(width 0.1)
				(type default)
			)
			(layer "F.Fab")
		)
		(fp_line
			(start -0.67945 -0.305054)
			(end -0.12065 -0.305054)
			(stroke
				(width 0.1)
				(type default)
			)
			(layer "F.Fab")
		)
		(fp_line
			(start -0.12065 -0.305054)
			(end -0.12065 -0.2794)
			(stroke
				(width 0.1)
				(type default)
			)
			(layer "F.Fab")
		)
		(pad "1" smd circle
			(at -0.40005 0 270)
			(size 0 0)
			(layers "F.Cu" "F.Mask" "F.Paste")
			(net "P3V3_SSD6")
		)
		(pad "2" smd circle
			(at 0.40005 0 270)
			(size 0 0)
			(layers "F.Cu" "F.Mask" "F.Paste")
			(net "SSD6_LED_ISO_N")
		)
	)
	(footprint ""
		(layer "F.Cu")
		(at 268.506448 -86.235286 180)
		(property "Reference" "R1069"
			(at 0 0 180)
			(layer "F.SilkS")
			(hide yes)
			(effects
				(font
					(size 1.27 1.27)
				)
			)
		)
		(property "Value" ""
			(at 0 0 180)
			(layer "F.Fab")
			(effects
				(font
					(size 1.27 1.27)
				)
			)
		)
		(duplicate_pad_numbers_are_jumpers no)
		(fp_line
			(start 0.7874 0.4064)
			(end -0.7874 0.4064)
			(stroke
				(width 0.1524)
				(type default)
			)
			(layer "F.SilkS")
		)
		(fp_line
			(start 0.7874 -0.4064)
			(end 0.7874 0.4064)
			(stroke
				(width 0.1524)
				(type default)
			)
			(layer "F.SilkS")
		)
		(fp_line
			(start -0.7874 0.4064)
			(end -0.7874 -0.4064)
			(stroke
				(width 0.1524)
				(type default)
			)
			(layer "F.SilkS")
		)
		(fp_line
			(start -0.7874 -0.4064)
			(end 0.7874 -0.4064)
			(stroke
				(width 0.1524)
				(type default)
			)
			(layer "F.SilkS")
		)
		(fp_line
			(start 0.67945 0.3048)
			(end 0.120396 0.3048)
			(stroke
				(width 0.1)
				(type default)
			)
			(layer "F.Fab")
		)
		(fp_line
			(start 0.67945 -0.3048)
			(end 0.67945 0.3048)
			(stroke
				(width 0.1)
				(type default)
			)
			(layer "F.Fab")
		)
		(fp_line
			(start 0.12065 -0.2794)
			(end 0.12065 -0.3048)
			(stroke
				(width 0.1)
				(type default)
			)
			(layer "F.Fab")
		)
		(fp_line
			(start 0.12065 -0.3048)
			(end 0.67945 -0.3048)
			(stroke
				(width 0.1)
				(type default)
			)
			(layer "F.Fab")
		)
		(fp_line
			(start 0.120396 0.3048)
			(end 0.120396 0.2794)
			(stroke
				(width 0.1)
				(type default)
			)
			(layer "F.Fab")
		)
		(fp_line
			(start 0.120396 0.2794)
			(end -0.12065 0.2794)
			(stroke
				(width 0.1)
				(type default)
			)
			(layer "F.Fab")
		)
		(fp_line
			(start -0.12065 0.3048)
			(end -0.67945 0.3048)
			(stroke
				(width 0.1)
				(type default)
			)
			(layer "F.Fab")
		)
		(fp_line
			(start -0.12065 0.2794)
			(end -0.12065 0.3048)
			(stroke
				(width 0.1)
				(type default)
			)
			(layer "F.Fab")
		)
		(fp_line
			(start -0.12065 -0.2794)
			(end 0.12065 -0.2794)
			(stroke
				(width 0.1)
				(type default)
			)
			(layer "F.Fab")
		)
		(fp_line
			(start -0.12065 -0.305054)
			(end -0.12065 -0.2794)
			(stroke
				(width 0.1)
				(type default)
			)
			(layer "F.Fab")
		)
		(fp_line
			(start -0.67945 0.3048)
			(end -0.67945 -0.305054)
			(stroke
				(width 0.1)
				(type default)
			)
			(layer "F.Fab")
		)
		(fp_line
			(start -0.67945 -0.305054)
			(end -0.12065 -0.305054)
			(stroke
				(width 0.1)
				(type default)
			)
			(layer "F.Fab")
		)
		(pad "1" smd circle
			(at -0.40005 0 180)
			(size 0 0)
			(layers "F.Cu" "F.Mask" "F.Paste")
			(net "GND")
		)
		(pad "2" smd circle
			(at 0.40005 0 180)
			(size 0 0)
			(layers "F.Cu" "F.Mask" "F.Paste")
			(net "CLK_BUFFER_DB2000QL_OE0_N")
		)
	)
	(footprint ""
		(layer "F.Cu")
		(at 137.27684 -124.008134 90)
		(property "Reference" "PD56"
			(at -3.390392 2.350516 90)
			(unlocked yes)
			(layer "F.SilkS")
			(effects
				(font
					(size 0.7874 0.5842)
					(thickness 0.1524)
				)
				(justify left)
			)
		)
		(property "Value" ""
			(at 0 0 90)
			(layer "F.Fab")
			(effects
				(font
					(size 1.27 1.27)
				)
			)
		)
		(duplicate_pad_numbers_are_jumpers no)
		(fp_line
			(start 4.107942 -1.459992)
			(end 4.107942 1.459992)
			(stroke
				(width 0.1524)
				(type default)
			)
			(layer "F.SilkS")
		)
		(fp_line
			(start -3.400044 -1.459992)
			(end 4.107942 -1.459992)
			(stroke
				(width 0.1524)
				(type default)
			)
			(layer "F.SilkS")
		)
		(fp_line
			(start 4.107942 1.459992)
			(end -3.400044 1.459992)
			(stroke
				(width 0.1524)
				(type default)
			)
			(layer "F.SilkS")
		)
		(fp_line
			(start -3.400044 1.459992)
			(end -3.400044 -1.459992)
			(stroke
				(width 0.1524)
				(type default)
			)
			(layer "F.SilkS")
		)
		(fp_poly
			(pts
				(xy 4.107942 -1.459992) (xy 4.107942 1.459992) (xy 3.308096 1.459992) (xy 3.308096 -1.459992)
			)
			(stroke
				(width 0)
				(type default)
			)
			(fill yes)
			(layer "F.SilkS")
		)
		(fp_line
			(start 2.29997 -1.459992)
			(end 2.29997 1.459992)
			(stroke
				(width 0.1)
				(type default)
			)
			(layer "F.Fab")
		)
		(fp_line
			(start -2.29997 -1.459992)
			(end 2.29997 -1.459992)
			(stroke
				(width 0.1)
				(type default)
			)
			(layer "F.Fab")
		)
		(fp_line
			(start 2.29997 1.459992)
			(end -2.29997 1.459992)
			(stroke
				(width 0.1)
				(type default)
			)
			(layer "F.Fab")
		)
		(fp_line
			(start -2.29997 1.459992)
			(end -2.29997 -1.459992)
			(stroke
				(width 0.1)
				(type default)
			)
			(layer "F.Fab")
		)
		(fp_text user "+"
			(at -4.7752 -0.12065 90)
			(unlocked yes)
			(layer "F.SilkS")
			(effects
				(font
					(size 1.905 1.4224)
					(thickness 0.1524)
				)
				(justify left)
			)
		)
		(fp_text user "-"
			(at 5.4102 0.29845 270)
			(unlocked yes)
			(layer "F.SilkS")
			(effects
				(font
					(size 1.905 1.4224)
					(thickness 0.1524)
				)
				(justify left)
			)
		)
		(fp_text user "+"
			(at -4.7752 -0.12065 90)
			(unlocked yes)
			(layer "F.Fab")
			(effects
				(font
					(size 1.905 1.4224)
					(thickness 0.1524)
				)
				(justify left)
			)
		)
		(fp_text user "-"
			(at 5.4102 0.29845 270)
			(unlocked yes)
			(layer "F.Fab")
			(effects
				(font
					(size 1.905 1.4224)
					(thickness 0.1524)
				)
				(justify left)
			)
		)
		(pad "A" smd rect
			(at -1.999996 0 180)
			(size 1.7018 2.5146)
			(layers "F.Cu" "F.Mask" "F.Paste")
			(net "GND")
		)
		(pad "C" smd rect
			(at 1.999996 0 180)
			(size 1.7018 2.5146)
			(layers "F.Cu" "F.Mask" "F.Paste")
			(net "P3V3_NIC2")
		)
	)
)
